# BASEBOARD_FAB2 (Tioga Pass) — schematic netlist excerpt (pin names and nets, part order shuffled) for the footprints in the layout excerpt that follows; sources: Cadence DE-HDL packaged netlist, KiCad conversion of Wiwynn_Tioga_Pass_MB.brd

C2M1  CAP_A  22.0UF 4V 20% X6S  pkg 0603V  page 130 : A = P1V8_PCH_STBY ; B = GND
C3L14  CAPP  470UF 2.5V 20% ALUM  pkg 3018  page 220 : A = PVDDQ_DEF ; B = GND
SH4L2  SHUNT  EMPTY  pkg SH0201  page 220 : A = VSENSE_PVDDQ_DEF_P ; B = PVDDQ_DEF

(kicad_pcb
	(version 20260206)
	(generator "pcbnew")
	(generator_version "10.0")
	(general
		(thickness 1.6)
		(legacy_teardrops no)
	)
	(paper "A4")
	(title_block
		(title "Wiwynn_Tioga_Pass_MB.brd")
		(comment 1 "Tioga Pass / footprints 3570-3572 of 4770")
	)
	(layers
		(0 "F.Cu" signal "TOP")
		(4 "In1.Cu" signal "L2GND")
		(6 "In2.Cu" signal "L3")
		(8 "In3.Cu" signal "L4GND")
		(10 "In4.Cu" signal "L5")
		(12 "In5.Cu" signal "L6GND")
		(14 "In6.Cu" signal "L7VCC")
		(16 "In7.Cu" signal "L8VCC")
		(18 "In8.Cu" signal "L9GND")
		(20 "In9.Cu" signal "L10")
		(22 "In10.Cu" signal "L11GND")
		(24 "In11.Cu" signal "L12")
		(26 "In12.Cu" signal "L13GND")
		(2 "B.Cu" signal "BOTTOM")
		(9 "F.Adhes" user "F.Adhesive")
		(11 "B.Adhes" user "B.Adhesive")
		(13 "F.Paste" user "Package Geometry/Pastemask Top")
		(15 "B.Paste" user "Package Geometry/Pastemask Bottom")
		(5 "F.SilkS" user "Ref Des/Silkscreen Top")
		(7 "B.SilkS" user "Ref Des/Silkscreen Bottom")
		(1 "F.Mask" user "Board Geometry/Soldermask Top")
		(3 "B.Mask" user "Board Geometry/Soldermask Bottom")
		(17 "Dwgs.User" user "User.Drawings")
		(19 "Cmts.User" user "User.Comments")
		(21 "Eco1.User" user "User.Eco1")
		(23 "Eco2.User" user "User.Eco2")
		(25 "Edge.Cuts" user "Board Geometry/Outline")
		(27 "Margin" user)
		(31 "F.CrtYd" user "Package Geometry/Place Bound Top")
		(29 "B.CrtYd" user "Package Geometry/Place Bound Bottom")
		(35 "F.Fab" user "Ref Des/Assembly Top")
		(33 "B.Fab" user "Ref Des/Assembly Bottom")
	)
	(footprint ""
		(layer "B.Cu")
		(at 411.0355 -130.6068 90)
		(property "Reference" "C2M1"
			(at 0 0 90)
			(layer "B.SilkS")
			(hide yes)
			(effects
				(font
					(size 1.27 1.27)
				)
				(justify mirror)
			)
		)
		(property "Value" ""
			(at 0 0 90)
			(layer "B.Fab")
			(effects
				(font
					(size 1.27 1.27)
				)
				(justify mirror)
			)
		)
		(duplicate_pad_numbers_are_jumpers no)
		(fp_poly
			(pts
				(xy 0.4953 -0.2032) (xy -0.4953 -0.2032) (xy -0.4953 1.6002) (xy 0.4953 1.6002)
			)
			(stroke
				(width 0)
				(type default)
			)
			(fill no)
			(layer "B.CrtYd")
		)
		(fp_line
			(start 0.4953 -0.2032)
			(end -0.4953 -0.2032)
			(stroke
				(width 0.1)
				(type default)
			)
			(layer "B.Fab")
		)
		(fp_line
			(start -0.4953 -0.2032)
			(end -0.4953 1.6002)
			(stroke
				(width 0.1)
				(type default)
			)
			(layer "B.Fab")
		)
		(fp_line
			(start 0.4953 1.6002)
			(end 0.4953 -0.2032)
			(stroke
				(width 0.1)
				(type default)
			)
			(layer "B.Fab")
		)
		(fp_line
			(start -0.4953 1.6002)
			(end 0.4953 1.6002)
			(stroke
				(width 0.1)
				(type default)
			)
			(layer "B.Fab")
		)
		(pad "1" smd rect
			(at 0 0 270)
			(size 0.762 0.889)
			(layers "B.Cu" "B.Mask" "B.Paste")
			(net "P1V8_PCH_STBY")
		)
		(pad "2" smd rect
			(at 0 1.397 270)
			(size 0.762 0.889)
			(layers "B.Cu" "B.Mask" "B.Paste")
			(net "GND")
		)
		(zone
			(layer "B.Cu")
			(hatch none 0.5)
			(connect_pads
				(clearance 0)
			)
			(min_thickness 0.25)
			(keepout
				(tracks not_allowed)
				(vias allowed)
				(pads allowed)
				(copperpour not_allowed)
				(footprints allowed)
			)
			(placement
				(enabled no)
				(sheetname "")
			)
			(fill
				(thermal_gap 0.5)
				(thermal_bridge_width 0.5)
				(island_removal_mode 0)
			)
			(polygon
				(pts
					(xy 411.48 -130.9878) (xy 411.48 -130.2258) (xy 411.988 -130.2258) (xy 411.988 -130.9878)
				)
			)
		)
	)
	(footprint ""
		(layer "B.Cu")
		(at 334.01 -150.368 90)
		(property "Reference" "C3L14"
			(at -2.18567 9.525 0)
			(unlocked yes)
			(layer "B.SilkS")
			(effects
				(font
					(size 0.7874 0.5842)
					(thickness 0.1524)
				)
				(justify mirror)
			)
		)
		(property "Value" ""
			(at 0 0 90)
			(layer "B.Fab")
			(effects
				(font
					(size 1.27 1.27)
				)
				(justify mirror)
			)
		)
		(duplicate_pad_numbers_are_jumpers no)
		(fp_line
			(start 2.563114 -1.616456)
			(end 2.563114 1.633728)
			(stroke
				(width 0.1524)
				(type default)
			)
			(layer "B.SilkS")
		)
		(fp_line
			(start 1.6002 -1.616456)
			(end 2.563114 -1.616456)
			(stroke
				(width 0.1524)
				(type default)
			)
			(layer "B.SilkS")
		)
		(fp_line
			(start -1.6002 -1.616456)
			(end -2.504948 -1.616456)
			(stroke
				(width 0.1524)
				(type default)
			)
			(layer "B.SilkS")
		)
		(fp_line
			(start -2.504948 -1.616456)
			(end -2.504948 1.633728)
			(stroke
				(width 0.1524)
				(type default)
			)
			(layer "B.SilkS")
		)
		(fp_line
			(start 2.563114 1.633728)
			(end 1.6002 1.633728)
			(stroke
				(width 0.1524)
				(type default)
			)
			(layer "B.SilkS")
		)
		(fp_line
			(start -2.504948 1.633728)
			(end -1.6002 1.633728)
			(stroke
				(width 0.1524)
				(type default)
			)
			(layer "B.SilkS")
		)
		(fp_line
			(start 2.286 7.366)
			(end 2.286 1.632712)
			(stroke
				(width 0.1524)
				(type default)
			)
			(layer "B.SilkS")
		)
		(fp_line
			(start 2.286 7.366)
			(end 1.60147 7.366)
			(stroke
				(width 0.1524)
				(type default)
			)
			(layer "B.SilkS")
		)
		(fp_line
			(start -2.286 7.366)
			(end -2.286 1.63195)
			(stroke
				(width 0.1524)
				(type default)
			)
			(layer "B.SilkS")
		)
		(fp_line
			(start -2.286 7.366)
			(end -1.600708 7.366)
			(stroke
				(width 0.1524)
				(type default)
			)
			(layer "B.SilkS")
		)
		(fp_rect
			(start 2.286 7.366)
			(end -2.286 -0.254)
			(stroke
				(width 0)
				(type default)
			)
			(fill no)
			(layer "B.CrtYd")
		)
		(fp_line
			(start 2.286 -0.254)
			(end -2.286 -0.254)
			(stroke
				(width 0.1)
				(type default)
			)
			(layer "B.Fab")
		)
		(fp_line
			(start -2.286 -0.254)
			(end -2.286 7.366)
			(stroke
				(width 0.1)
				(type default)
			)
			(layer "B.Fab")
		)
		(fp_line
			(start 2.286 7.366)
			(end 2.286 -0.254)
			(stroke
				(width 0.1)
				(type default)
			)
			(layer "B.Fab")
		)
		(fp_line
			(start -2.286 7.366)
			(end 2.286 7.366)
			(stroke
				(width 0.1)
				(type default)
			)
			(layer "B.Fab")
		)
		(pad "1" smd rect
			(at 0 0 270)
			(size 2.54 3.048)
			(layers "B.Cu" "B.Mask" "B.Paste")
			(net "PVDDQ_DEF")
		)
		(pad "2" smd rect
			(at 0 7.112 270)
			(size 2.54 3.048)
			(layers "B.Cu" "B.Mask" "B.Paste")
			(net "GND")
		)
	)
	(footprint ""
		(layer "B.Cu")
		(at 266.7762 -124.6886 90)
		(property "Reference" "SH4L2"
			(at 0 0 90)
			(layer "B.SilkS")
			(hide yes)
			(effects
				(font
					(size 1.27 1.27)
				)
				(justify mirror)
			)
		)
		(property "Value" ""
			(at 0 0 90)
			(layer "B.Fab")
			(effects
				(font
					(size 1.27 1.27)
				)
				(justify mirror)
			)
		)
		(duplicate_pad_numbers_are_jumpers no)
		(fp_poly
			(pts
				(xy 0.1651 -0.0508) (xy 0.1651 0.5842) (xy -0.1651 0.5842) (xy -0.1651 -0.0508)
			)
			(stroke
				(width 0)
				(type default)
			)
			(fill no)
			(layer "B.CrtYd")
		)
		(fp_line
			(start 0.1651 -0.0508)
			(end -0.1651 -0.0508)
			(stroke
				(width 0.1)
				(type default)
			)
			(layer "B.Fab")
		)
		(fp_line
			(start -0.1651 -0.0508)
			(end -0.1651 0.5842)
			(stroke
				(width 0.1)
				(type default)
			)
			(layer "B.Fab")
		)
		(fp_line
			(start 0.1651 0.5842)
			(end 0.1651 -0.0508)
			(stroke
				(width 0.1)
				(type default)
			)
			(layer "B.Fab")
		)
		(fp_line
			(start -0.1651 0.5842)
			(end 0.1651 0.5842)
			(stroke
				(width 0.1)
				(type default)
			)
			(layer "B.Fab")
		)
		(pad "1" smd custom
			(at 0 0 90)
			(size 0.0762 0.0762)
			(layers "B.Cu" "B.Mask" "B.Paste")
			(net "VSENSE_PVDDQ_DEF_P")
			(options
				(clearance outline)
				(anchor circle)
			)
			(primitives
				(gr_poly
					(pts
						(arc
							(start -0.1524 0.10795)
							(mid -0.098518 0.130268)
							(end -0.0762 0.18415)
						)
						(xy -0.0762 0.22225) (xy 0.0762 0.22225)
						(arc
							(start 0.0762 0.18415)
							(mid 0.098518 0.130268)
							(end 0.1524 0.10795)
						)
						(xy 0.1524 -0.22225) (xy -0.1524 -0.22225)
					)
					(width 0)
					(fill yes)
				)
			)
		)
		(pad "2" smd custom
			(at 0 0.5334 270)
			(size 0.0762 0.0762)
			(layers "B.Cu" "B.Mask" "B.Paste")
			(net "PVDDQ_DEF")
			(options
				(clearance outline)
				(anchor circle)
			)
			(primitives
				(gr_poly
					(pts
						(arc
							(start -0.1524 0.10795)
							(mid -0.098518 0.130268)
							(end -0.0762 0.18415)
						)
						(xy -0.0762 0.22225) (xy 0.0762 0.22225)
						(arc
							(start 0.0762 0.18415)
							(mid 0.098518 0.130268)
							(end 0.1524 0.10795)
						)
						(xy 0.1524 -0.22225) (xy -0.1524 -0.22225)
					)
					(width 0)
					(fill yes)
				)
			)
		)
	)
)
